# BASEBOARD_FAB2 (Tioga Pass) — schematic netlist excerpt (pin names and nets, part order shuffled) for the footprints in the layout excerpt that follows; sources: Cadence DE-HDL packaged netlist, KiCad conversion of Wiwynn_Tioga_Pass_MB.brd

C2A12  CAP_A  47UF 4V 20% X5R  pkg 0603V  page 228 : A = PVDDQ_KLM ; B = GND
R3D18  RES  0.0 5% CHIP  pkg 0402  page 97 : A = H_CPU0_FAST_WAKE_N ; B = H_CPU1_FAST_WAKE_N
R25W153  RES  4.75K 1% CHIP  pkg 0402  page 157 : A = P3V3_STBY ; B = RST_BMC_SRST_N

(kicad_pcb
	(version 20260206)
	(generator "pcbnew")
	(generator_version "10.0")
	(general
		(thickness 1.6)
		(legacy_teardrops no)
	)
	(paper "A4")
	(title_block
		(title "Wiwynn_Tioga_Pass_MB.brd")
		(comment 1 "Tioga Pass / footprints 664-666 of 4770")
	)
	(layers
		(0 "F.Cu" signal "TOP")
		(4 "In1.Cu" signal "L2GND")
		(6 "In2.Cu" signal "L3")
		(8 "In3.Cu" signal "L4GND")
		(10 "In4.Cu" signal "L5")
		(12 "In5.Cu" signal "L6GND")
		(14 "In6.Cu" signal "L7VCC")
		(16 "In7.Cu" signal "L8VCC")
		(18 "In8.Cu" signal "L9GND")
		(20 "In9.Cu" signal "L10")
		(22 "In10.Cu" signal "L11GND")
		(24 "In11.Cu" signal "L12")
		(26 "In12.Cu" signal "L13GND")
		(2 "B.Cu" signal "BOTTOM")
		(9 "F.Adhes" user "F.Adhesive")
		(11 "B.Adhes" user "B.Adhesive")
		(13 "F.Paste" user "Package Geometry/Pastemask Top")
		(15 "B.Paste" user "Package Geometry/Pastemask Bottom")
		(5 "F.SilkS" user "Ref Des/Silkscreen Top")
		(7 "B.SilkS" user "Ref Des/Silkscreen Bottom")
		(1 "F.Mask" user "Board Geometry/Soldermask Top")
		(3 "B.Mask" user "Board Geometry/Soldermask Bottom")
		(17 "Dwgs.User" user "User.Drawings")
		(19 "Cmts.User" user "User.Comments")
		(21 "Eco1.User" user "User.Eco1")
		(23 "Eco2.User" user "User.Eco2")
		(25 "Edge.Cuts" user "Board Geometry/Outline")
		(27 "Margin" user)
		(31 "F.CrtYd" user "Package Geometry/Place Bound Top")
		(29 "B.CrtYd" user "Package Geometry/Place Bound Bottom")
		(35 "F.Fab" user "Ref Des/Assembly Top")
		(33 "B.Fab" user "Ref Des/Assembly Bottom")
	)
	(footprint ""
		(layer "F.Cu")
		(at 446.786 -16.002 90)
		(property "Reference" "R25W153"
			(at -0.8382 -0.67818 90)
			(unlocked yes)
			(layer "F.SilkS")
			(effects
				(font
					(size 0.4064 0.254)
					(thickness 0.1524)
				)
				(justify left)
			)
		)
		(property "Value" ""
			(at 0 0 90)
			(layer "F.Fab")
			(effects
				(font
					(size 1.27 1.27)
				)
			)
		)
		(duplicate_pad_numbers_are_jumpers no)
		(fp_poly
			(pts
				(xy -0.2794 -0.1016) (xy 0.2794 -0.1016) (xy 0.2794 0.9906) (xy -0.2794 0.9906)
			)
			(stroke
				(width 0)
				(type default)
			)
			(fill no)
			(layer "F.CrtYd")
		)
		(fp_line
			(start 0.2794 -0.1016)
			(end -0.2794 -0.1016)
			(stroke
				(width 0.1)
				(type default)
			)
			(layer "F.Fab")
		)
		(fp_line
			(start -0.2794 -0.1016)
			(end -0.2794 0.9906)
			(stroke
				(width 0.1)
				(type default)
			)
			(layer "F.Fab")
		)
		(fp_line
			(start 0.2794 0.9906)
			(end 0.2794 -0.1016)
			(stroke
				(width 0.1)
				(type default)
			)
			(layer "F.Fab")
		)
		(fp_line
			(start -0.2794 0.9906)
			(end 0.2794 0.9906)
			(stroke
				(width 0.1)
				(type default)
			)
			(layer "F.Fab")
		)
		(pad "1" smd rect
			(at 0 0 90)
			(size 0.508 0.508)
			(layers "F.Cu" "F.Mask" "F.Paste")
			(net "P3V3_STBY")
		)
		(pad "2" smd rect
			(at 0 0.889 90)
			(size 0.508 0.508)
			(layers "F.Cu" "F.Mask" "F.Paste")
			(net "RST_BMC_SRST_N")
		)
		(zone
			(layer "F.Cu")
			(hatch none 0.5)
			(connect_pads
				(clearance 0)
			)
			(min_thickness 0.25)
			(keepout
				(tracks allowed)
				(vias not_allowed)
				(pads allowed)
				(copperpour not_allowed)
				(footprints allowed)
			)
			(placement
				(enabled no)
				(sheetname "")
			)
			(fill
				(thermal_gap 0.5)
				(thermal_bridge_width 0.5)
				(island_removal_mode 0)
			)
			(polygon
				(pts
					(xy 447.04 -15.748) (xy 447.04 -16.256) (xy 447.421 -16.256) (xy 447.421 -15.748)
				)
			)
		)
		(zone
			(layer "F.Cu")
			(hatch none 0.5)
			(connect_pads
				(clearance 0)
			)
			(min_thickness 0.25)
			(keepout
				(tracks not_allowed)
				(vias allowed)
				(pads allowed)
				(copperpour not_allowed)
				(footprints allowed)
			)
			(placement
				(enabled no)
				(sheetname "")
			)
			(fill
				(thermal_gap 0.5)
				(thermal_bridge_width 0.5)
				(island_removal_mode 0)
			)
			(polygon
				(pts
					(xy 447.421 -15.748) (xy 447.421 -16.256) (xy 447.04 -16.256) (xy 447.04 -15.748)
				)
			)
		)
	)
	(footprint ""
		(layer "F.Cu")
		(at 88.392 -140.208 90)
		(property "Reference" "C2A12"
			(at 1.848866 0.752348 90)
			(unlocked yes)
			(layer "F.SilkS")
			(effects
				(font
					(size 1.27 0.9652)
					(thickness 0.1524)
				)
			)
		)
		(property "Value" ""
			(at 0 0 90)
			(layer "F.Fab")
			(effects
				(font
					(size 1.27 1.27)
				)
			)
		)
		(duplicate_pad_numbers_are_jumpers no)
		(fp_rect
			(start -0.500126 1.598422)
			(end 0.500126 -0.201422)
			(stroke
				(width 0)
				(type default)
			)
			(fill no)
			(layer "F.CrtYd")
		)
		(fp_line
			(start 0.500126 -0.201422)
			(end 0.500126 1.598422)
			(stroke
				(width 0.1)
				(type default)
			)
			(layer "F.Fab")
		)
		(fp_line
			(start -0.500126 -0.201422)
			(end 0.500126 -0.201422)
			(stroke
				(width 0.1)
				(type default)
			)
			(layer "F.Fab")
		)
		(fp_line
			(start 0.500126 1.598422)
			(end -0.500126 1.598422)
			(stroke
				(width 0.1)
				(type default)
			)
			(layer "F.Fab")
		)
		(fp_line
			(start -0.500126 1.598422)
			(end -0.500126 -0.201422)
			(stroke
				(width 0.1)
				(type default)
			)
			(layer "F.Fab")
		)
		(pad "1" smd rect
			(at 0 0)
			(size 0.889 0.9906)
			(layers "F.Cu" "F.Mask" "F.Paste")
			(net "PVDDQ_KLM")
		)
		(pad "2" smd rect
			(at 0 1.397)
			(size 0.889 0.9906)
			(layers "F.Cu" "F.Mask" "F.Paste")
			(net "GND")
		)
		(zone
			(layer "F.Cu")
			(hatch none 0.5)
			(connect_pads
				(clearance 0)
			)
			(min_thickness 0.25)
			(keepout
				(tracks not_allowed)
				(vias allowed)
				(pads allowed)
				(copperpour not_allowed)
				(footprints allowed)
			)
			(placement
				(enabled no)
				(sheetname "")
			)
			(fill
				(thermal_gap 0.5)
				(thermal_bridge_width 0.5)
				(island_removal_mode 0)
			)
			(polygon
				(pts
					(xy 89.3445 -139.7127) (xy 89.3445 -140.7033) (xy 88.8365 -140.7033) (xy 88.8365 -139.7127)
				)
			)
		)
		(zone
			(layer "F.Cu")
			(hatch none 0.5)
			(connect_pads
				(clearance 0)
			)
			(min_thickness 0.25)
			(keepout
				(tracks allowed)
				(vias not_allowed)
				(pads allowed)
				(copperpour not_allowed)
				(footprints allowed)
			)
			(placement
				(enabled no)
				(sheetname "")
			)
			(fill
				(thermal_gap 0.5)
				(thermal_bridge_width 0.5)
				(island_removal_mode 0)
			)
			(polygon
				(pts
					(xy 89.3445 -139.7127) (xy 89.3445 -140.7033) (xy 88.8365 -140.7033) (xy 88.8365 -139.7127)
				)
			)
		)
	)
	(footprint ""
		(layer "F.Cu")
		(at 161.723832 -71.43369)
		(property "Reference" "R3D18"
			(at 0 0 0)
			(layer "F.SilkS")
			(hide yes)
			(effects
				(font
					(size 1.27 1.27)
				)
			)
		)
		(property "Value" ""
			(at 0 0 0)
			(layer "F.Fab")
			(effects
				(font
					(size 1.27 1.27)
				)
			)
		)
		(duplicate_pad_numbers_are_jumpers no)
		(fp_poly
			(pts
				(xy -0.2794 -0.1016) (xy 0.2794 -0.1016) (xy 0.2794 0.9906) (xy -0.2794 0.9906)
			)
			(stroke
				(width 0)
				(type default)
			)
			(fill no)
			(layer "F.CrtYd")
		)
		(fp_line
			(start -0.2794 -0.1016)
			(end -0.2794 0.9906)
			(stroke
				(width 0.1)
				(type default)
			)
			(layer "F.Fab")
		)
		(fp_line
			(start -0.2794 0.9906)
			(end 0.2794 0.9906)
			(stroke
				(width 0.1)
				(type default)
			)
			(layer "F.Fab")
		)
		(fp_line
			(start 0.2794 -0.1016)
			(end -0.2794 -0.1016)
			(stroke
				(width 0.1)
				(type default)
			)
			(layer "F.Fab")
		)
		(fp_line
			(start 0.2794 0.9906)
			(end 0.2794 -0.1016)
			(stroke
				(width 0.1)
				(type default)
			)
			(layer "F.Fab")
		)
		(pad "1" smd rect
			(at 0 0)
			(size 0.508 0.508)
			(layers "F.Cu" "F.Mask" "F.Paste")
			(net "H_CPU0_FAST_WAKE_N")
		)
		(pad "2" smd rect
			(at 0 0.889)
			(size 0.508 0.508)
			(layers "F.Cu" "F.Mask" "F.Paste")
			(net "H_CPU1_FAST_WAKE_N")
		)
		(zone
			(layer "F.Cu")
			(hatch none 0.5)
			(connect_pads
				(clearance 0)
			)
			(min_thickness 0.25)
			(keepout
				(tracks allowed)
				(vias not_allowed)
				(pads allowed)
				(copperpour not_allowed)
				(footprints allowed)
			)
			(placement
				(enabled no)
				(sheetname "")
			)
			(fill
				(thermal_gap 0.5)
				(thermal_bridge_width 0.5)
				(island_removal_mode 0)
			)
			(polygon
				(pts
					(xy 161.469832 -71.17969) (xy 161.977832 -71.17969) (xy 161.977832 -70.79869) (xy 161.469832 -70.79869)
				)
			)
		)
		(zone
			(layer "F.Cu")
			(hatch none 0.5)
			(connect_pads
				(clearance 0)
			)
			(min_thickness 0.25)
			(keepout
				(tracks not_allowed)
				(vias allowed)
				(pads allowed)
				(copperpour not_allowed)
				(footprints allowed)
			)
			(placement
				(enabled no)
				(sheetname "")
			)
			(fill
				(thermal_gap 0.5)
				(thermal_bridge_width 0.5)
				(island_removal_mode 0)
			)
			(polygon
				(pts
					(xy 161.469832 -70.79869) (xy 161.977832 -70.79869) (xy 161.977832 -71.17969) (xy 161.469832 -71.17969)
				)
			)
		)
	)
)
